# S9S_MB_2U (Grand Teton) — schematic netlist excerpt (pin names and nets, part order shuffled) for the footprints in the layout excerpt that follows; sources: Cadence DE-HDL packaged netlist, KiCad conversion of 03242023_DA0F0TMBIJ0_F0T_Motherboard_J_brd_V01_OCP.brd

R705  Q_RES  10K 1% EMPTY  pkg 0402LF  page 129 : A = RST_PLD_CPU0_DRAM_GH_N ; B = GND
R2480  Q_RES  33.2 1% CHIP  pkg 0402LF  page 235 : A = SMB_PEHPCPU1_LVC3_SDA_R0 ; B = SMB_PEHPCPU1_LVC3_SDA

(kicad_pcb
	(version 20260206)
	(generator "pcbnew")
	(generator_version "10.0")
	(general
		(thickness 1.6)
		(legacy_teardrops no)
	)
	(paper "A4")
	(title_block
		(title "03242023_DA0F0TMBIJ0_F0T_Motherboard_J_brd_V01_OCP.brd")
		(comment 1 "Grand Teton / footprints 5945-5946 of 6105")
	)
	(layers
		(0 "F.Cu" signal "TOP")
		(4 "In1.Cu" signal "GND")
		(6 "In2.Cu" signal "IN1")
		(8 "In3.Cu" signal "GND1")
		(10 "In4.Cu" signal "IN2")
		(12 "In5.Cu" signal "GND2")
		(14 "In6.Cu" signal "IN3")
		(16 "In7.Cu" signal "GND3")
		(18 "In8.Cu" signal "VCC")
		(20 "In9.Cu" signal "VCC1")
		(22 "In10.Cu" signal "GND4")
		(24 "In11.Cu" signal "IN4")
		(26 "In12.Cu" signal "GND5")
		(28 "In13.Cu" signal "IN5")
		(30 "In14.Cu" signal "GND6")
		(32 "In15.Cu" signal "IN6")
		(34 "In16.Cu" signal "GND7")
		(2 "B.Cu" signal "BOTTOM")
		(9 "F.Adhes" user "F.Adhesive")
		(11 "B.Adhes" user "B.Adhesive")
		(13 "F.Paste" user "Package Geometry/Pastemask Top")
		(15 "B.Paste" user "Package Geometry/Pastemask Bottom")
		(5 "F.SilkS" user "Ref Des/Silkscreen Top")
		(7 "B.SilkS" user "Ref Des/Silkscreen Bottom")
		(1 "F.Mask" user "Board Geometry/Soldermask Top")
		(3 "B.Mask" user "Board Geometry/Soldermask Bottom")
		(17 "Dwgs.User" user "User.Drawings")
		(19 "Cmts.User" user "User.Comments")
		(21 "Eco1.User" user "User.Eco1")
		(23 "Eco2.User" user "User.Eco2")
		(25 "Edge.Cuts" user "Board Geometry/Outline")
		(27 "Margin" user)
		(31 "F.CrtYd" user "Package Geometry/Place Bound Top")
		(29 "B.CrtYd" user "Package Geometry/Place Bound Bottom")
		(35 "F.Fab" user "Ref Des/Assembly Top")
		(33 "B.Fab" user "Ref Des/Assembly Bottom")
	)
	(footprint ""
		(layer "B.Cu")
		(at 433.564792 -193.565272 -90)
		(property "Reference" "R705"
			(at 0 0 90)
			(layer "B.SilkS")
			(hide yes)
			(effects
				(font
					(size 1.27 1.27)
				)
				(justify mirror)
			)
		)
		(property "Value" ""
			(at 0 0 90)
			(layer "B.Fab")
			(effects
				(font
					(size 1.27 1.27)
				)
				(justify mirror)
			)
		)
		(duplicate_pad_numbers_are_jumpers no)
		(fp_line
			(start -0.7874 0.4064)
			(end 0.7874 0.4064)
			(stroke
				(width 0.1524)
				(type default)
			)
			(layer "B.SilkS")
		)
		(fp_line
			(start 0.7874 0.4064)
			(end 0.7874 -0.4064)
			(stroke
				(width 0.1524)
				(type default)
			)
			(layer "B.SilkS")
		)
		(fp_line
			(start -0.7874 -0.4064)
			(end -0.7874 0.4064)
			(stroke
				(width 0.1524)
				(type default)
			)
			(layer "B.SilkS")
		)
		(fp_line
			(start 0.7874 -0.4064)
			(end -0.7874 -0.4064)
			(stroke
				(width 0.1524)
				(type default)
			)
			(layer "B.SilkS")
		)
		(fp_line
			(start -0.67945 0.3048)
			(end -0.120396 0.3048)
			(stroke
				(width 0.1)
				(type default)
			)
			(layer "B.Fab")
		)
		(fp_line
			(start -0.120396 0.3048)
			(end -0.120396 0.2794)
			(stroke
				(width 0.1)
				(type default)
			)
			(layer "B.Fab")
		)
		(fp_line
			(start 0.12065 0.3048)
			(end 0.67945 0.3048)
			(stroke
				(width 0.1)
				(type default)
			)
			(layer "B.Fab")
		)
		(fp_line
			(start 0.67945 0.3048)
			(end 0.67945 -0.305054)
			(stroke
				(width 0.1)
				(type default)
			)
			(layer "B.Fab")
		)
		(fp_line
			(start -0.120396 0.2794)
			(end 0.12065 0.2794)
			(stroke
				(width 0.1)
				(type default)
			)
			(layer "B.Fab")
		)
		(fp_line
			(start 0.12065 0.2794)
			(end 0.12065 0.3048)
			(stroke
				(width 0.1)
				(type default)
			)
			(layer "B.Fab")
		)
		(fp_line
			(start -0.12065 -0.2794)
			(end -0.12065 -0.3048)
			(stroke
				(width 0.1)
				(type default)
			)
			(layer "B.Fab")
		)
		(fp_line
			(start 0.12065 -0.2794)
			(end -0.12065 -0.2794)
			(stroke
				(width 0.1)
				(type default)
			)
			(layer "B.Fab")
		)
		(fp_line
			(start -0.67945 -0.3048)
			(end -0.67945 0.3048)
			(stroke
				(width 0.1)
				(type default)
			)
			(layer "B.Fab")
		)
		(fp_line
			(start -0.12065 -0.3048)
			(end -0.67945 -0.3048)
			(stroke
				(width 0.1)
				(type default)
			)
			(layer "B.Fab")
		)
		(fp_line
			(start 0.12065 -0.305054)
			(end 0.12065 -0.2794)
			(stroke
				(width 0.1)
				(type default)
			)
			(layer "B.Fab")
		)
		(fp_line
			(start 0.67945 -0.305054)
			(end 0.12065 -0.305054)
			(stroke
				(width 0.1)
				(type default)
			)
			(layer "B.Fab")
		)
		(pad "1" smd circle
			(at 0.40005 0 90)
			(size 0 0)
			(layers "B.Cu" "B.Mask" "B.Paste")
			(net "RST_PLD_CPU0_DRAM_GH_N")
		)
		(pad "2" smd circle
			(at -0.40005 0 90)
			(size 0 0)
			(layers "B.Cu" "B.Mask" "B.Paste")
			(net "GND")
		)
	)
	(footprint ""
		(layer "B.Cu")
		(at 12.666472 -183.482996)
		(property "Reference" "R2480"
			(at 0 0 0)
			(layer "B.SilkS")
			(hide yes)
			(effects
				(font
					(size 1.27 1.27)
				)
				(justify mirror)
			)
		)
		(property "Value" ""
			(at 0 0 0)
			(layer "B.Fab")
			(effects
				(font
					(size 1.27 1.27)
				)
				(justify mirror)
			)
		)
		(duplicate_pad_numbers_are_jumpers no)
		(fp_line
			(start -0.7874 -0.4064)
			(end -0.7874 0.4064)
			(stroke
				(width 0.1524)
				(type default)
			)
			(layer "B.SilkS")
		)
		(fp_line
			(start -0.7874 0.4064)
			(end 0.7874 0.4064)
			(stroke
				(width 0.1524)
				(type default)
			)
			(layer "B.SilkS")
		)
		(fp_line
			(start 0.7874 -0.4064)
			(end -0.7874 -0.4064)
			(stroke
				(width 0.1524)
				(type default)
			)
			(layer "B.SilkS")
		)
		(fp_line
			(start 0.7874 0.4064)
			(end 0.7874 -0.4064)
			(stroke
				(width 0.1524)
				(type default)
			)
			(layer "B.SilkS")
		)
		(fp_line
			(start -0.67945 -0.3048)
			(end -0.67945 0.3048)
			(stroke
				(width 0.1)
				(type default)
			)
			(layer "B.Fab")
		)
		(fp_line
			(start -0.67945 0.3048)
			(end -0.120396 0.3048)
			(stroke
				(width 0.1)
				(type default)
			)
			(layer "B.Fab")
		)
		(fp_line
			(start -0.12065 -0.3048)
			(end -0.67945 -0.3048)
			(stroke
				(width 0.1)
				(type default)
			)
			(layer "B.Fab")
		)
		(fp_line
			(start -0.12065 -0.2794)
			(end -0.12065 -0.3048)
			(stroke
				(width 0.1)
				(type default)
			)
			(layer "B.Fab")
		)
		(fp_line
			(start -0.120396 0.2794)
			(end 0.12065 0.2794)
			(stroke
				(width 0.1)
				(type default)
			)
			(layer "B.Fab")
		)
		(fp_line
			(start -0.120396 0.3048)
			(end -0.120396 0.2794)
			(stroke
				(width 0.1)
				(type default)
			)
			(layer "B.Fab")
		)
		(fp_line
			(start 0.12065 -0.305054)
			(end 0.12065 -0.2794)
			(stroke
				(width 0.1)
				(type default)
			)
			(layer "B.Fab")
		)
		(fp_line
			(start 0.12065 -0.2794)
			(end -0.12065 -0.2794)
			(stroke
				(width 0.1)
				(type default)
			)
			(layer "B.Fab")
		)
		(fp_line
			(start 0.12065 0.2794)
			(end 0.12065 0.3048)
			(stroke
				(width 0.1)
				(type default)
			)
			(layer "B.Fab")
		)
		(fp_line
			(start 0.12065 0.3048)
			(end 0.67945 0.3048)
			(stroke
				(width 0.1)
				(type default)
			)
			(layer "B.Fab")
		)
		(fp_line
			(start 0.67945 -0.305054)
			(end 0.12065 -0.305054)
			(stroke
				(width 0.1)
				(type default)
			)
			(layer "B.Fab")
		)
		(fp_line
			(start 0.67945 0.3048)
			(end 0.67945 -0.305054)
			(stroke
				(width 0.1)
				(type default)
			)
			(layer "B.Fab")
		)
		(pad "1" smd circle
			(at 0.40005 0 180)
			(size 0 0)
			(layers "B.Cu" "B.Mask" "B.Paste")
			(net "SMB_PEHPCPU1_LVC3_SDA_R0")
		)
		(pad "2" smd circle
			(at -0.40005 0 180)
			(size 0 0)
			(layers "B.Cu" "B.Mask" "B.Paste")
			(net "SMB_PEHPCPU1_LVC3_SDA")
		)
	)
)
